FILE_TYPE = CONNECTIVITY;
{Allegro Design Entry HDL 17.2-2016 S081 (4005846) 1/11/2022}
"PAGE_NUMBER" = 37;
0"NC";
1"M_A_CPU1_SA_DQ<31:0>";
2"M_A_CPU1_SB_DQ<31:0>";
3"M_A_CPU1_SA_CB<7:0>";
4"M_A_CPU1_SB_CB<7:0>";
5"M_A_CPU1_SA_DQS_DP<9:0>";
6"M_A_CPU1_SB_DQS_DP<9:0>";
7"M_A_CPU1_SA_CA<6:0>";
8"M_A_CPU1_SB_CA<6:0>";
9"M_A_CPU1_SA_DQS_DN<9:0>";
10"M_A_CPU1_SB_DQS_DN<9:0>";
11"M_A_CPU1_ALERT_N";
12"TP_M_A_CPU1_SA_TEST40";
13"TP_M_A_CPU1_SA_TEST39A";
14"M_A_CPU1_ALERT_R_N";
15"M_A_CPU1_CLK_DP<0>";
16"M_A_CPU1_CLK_DN<0>";
17"M_A_CPU1_SA_CS_N<0>";
18"M_A_CPU1_SA_CS_N<1>";
19"M_A_CPU1_SA_RSP<0>";
20"M_A_CPU1_SA_PAR";
21"M_A_CPU1_SB_CS_N<0>";
22"M_A_CPU1_SB_CS_N<1>";
23"M_A_CPU1_SB_RSP<0>";
24"M_A_CPU1_SB_PAR";
25"M_A_CPU1_RESET_N";
26"M_A_CPU1_SB_CA<6>";
27"M_A_CPU1_SA_CA<6>";
28"M_A_CPU1_SB_CA<5>";
29"M_A_CPU1_SA_CA<5>";
30"M_A_CPU1_SB_CA<4>";
31"M_A_CPU1_SA_CA<4>";
32"M_A_CPU1_SB_CA<3>";
33"M_A_CPU1_SA_CA<3>";
34"M_A_CPU1_SB_CA<2>";
35"M_A_CPU1_SA_CA<2>";
36"M_A_CPU1_SB_CA<1>";
37"M_A_CPU1_SA_CA<1>";
38"M_A_CPU1_SB_CA<0>";
39"M_A_CPU1_SA_CA<0>";
40"M_A_CPU1_SB_DQS_DN<9>";
41"M_A_CPU1_SB_DQS_DP<9>";
42"M_A_CPU1_SB_DQS_DP<0>";
43"M_A_CPU1_SB_DQS_DN<4>";
44"M_A_CPU1_SB_DQS_DN<3>";
45"M_A_CPU1_SB_DQS_DN<2>";
46"M_A_CPU1_SB_DQS_DN<1>";
47"M_A_CPU1_SB_DQS_DN<0>";
48"M_A_CPU1_SB_DQS_DP<8>";
49"M_A_CPU1_SB_DQS_DP<7>";
50"M_A_CPU1_SB_DQS_DP<6>";
51"M_A_CPU1_SB_DQS_DP<5>";
52"M_A_CPU1_SB_DQS_DP<4>";
53"M_A_CPU1_SB_DQS_DN<8>";
54"M_A_CPU1_SB_DQS_DP<3>";
55"M_A_CPU1_SB_DQS_DN<7>";
56"M_A_CPU1_SB_DQS_DP<2>";
57"M_A_CPU1_SB_DQS_DN<6>";
58"M_A_CPU1_SB_DQS_DP<1>";
59"M_A_CPU1_SB_DQS_DN<5>";
60"M_A_CPU1_SA_DQS_DP<6>";
61"M_A_CPU1_SA_DQS_DP<5>";
62"M_A_CPU1_SA_DQS_DN<9>";
63"M_A_CPU1_SA_DQS_DP<4>";
64"M_A_CPU1_SA_DQS_DN<8>";
65"M_A_CPU1_SA_DQS_DP<3>";
66"M_A_CPU1_SA_DQS_DN<7>";
67"M_A_CPU1_SA_DQS_DP<2>";
68"M_A_CPU1_SA_DQS_DN<6>";
69"M_A_CPU1_SA_DQS_DP<1>";
70"M_A_CPU1_SA_DQS_DN<5>";
71"M_A_CPU1_SA_DQS_DP<0>";
72"M_A_CPU1_SA_DQS_DN<4>";
73"M_A_CPU1_SA_DQS_DN<3>";
74"M_A_CPU1_SA_DQS_DN<2>";
75"M_A_CPU1_SA_DQS_DN<1>";
76"M_A_CPU1_SA_DQS_DN<0>";
77"M_A_CPU1_SA_DQS_DP<9>";
78"M_A_CPU1_SA_DQS_DP<8>";
79"M_A_CPU1_SA_DQS_DP<7>";
80"M_A_CPU1_SB_CB<7>";
81"M_A_CPU1_SB_CB<6>";
82"M_A_CPU1_SB_CB<5>";
83"M_A_CPU1_SB_CB<4>";
84"M_A_CPU1_SB_CB<3>";
85"M_A_CPU1_SB_CB<2>";
86"M_A_CPU1_SB_CB<1>";
87"M_A_CPU1_SB_CB<0>";
88"M_A_CPU1_SB_DQ<28>";
89"M_A_CPU1_SB_DQ<27>";
90"M_A_CPU1_SB_DQ<26>";
91"M_A_CPU1_SB_DQ<25>";
92"M_A_CPU1_SB_DQ<24>";
93"M_A_CPU1_SB_DQ<23>";
94"M_A_CPU1_SA_CB<7>";
95"M_A_CPU1_SA_CB<6>";
96"M_A_CPU1_SB_DQ<31>";
97"M_A_CPU1_SA_CB<5>";
98"M_A_CPU1_SB_DQ<30>";
99"M_A_CPU1_SA_CB<4>";
100"M_A_CPU1_SA_CB<3>";
101"M_A_CPU1_SA_CB<2>";
102"M_A_CPU1_SA_CB<1>";
103"M_A_CPU1_SA_CB<0>";
104"M_A_CPU1_SB_DQ<29>";
105"M_A_CPU1_SB_DQ<17>";
106"M_A_CPU1_SB_DQ<16>";
107"M_A_CPU1_SB_DQ<15>";
108"M_A_CPU1_SB_DQ<14>";
109"M_A_CPU1_SB_DQ<13>";
110"M_A_CPU1_SB_DQ<12>";
111"M_A_CPU1_SB_DQ<11>";
112"M_A_CPU1_SB_DQ<22>";
113"M_A_CPU1_SB_DQ<10>";
114"M_A_CPU1_SB_DQ<21>";
115"M_A_CPU1_SB_DQ<20>";
116"M_A_CPU1_SB_DQ<9>";
117"M_A_CPU1_SB_DQ<8>";
118"M_A_CPU1_SB_DQ<7>";
119"M_A_CPU1_SB_DQ<6>";
120"M_A_CPU1_SB_DQ<5>";
121"M_A_CPU1_SB_DQ<4>";
122"M_A_CPU1_SB_DQ<19>";
123"M_A_CPU1_SB_DQ<18>";
124"M_A_CPU1_SB_DQ<2>";
125"M_A_CPU1_SB_DQ<1>";
126"M_A_CPU1_SB_DQ<0>";
127"M_A_CPU1_SA_DQ<19>";
128"M_A_CPU1_SA_DQ<18>";
129"M_A_CPU1_SA_DQ<29>";
130"M_A_CPU1_SA_DQ<28>";
131"M_A_CPU1_SA_DQ<27>";
132"M_A_CPU1_SA_DQ<26>";
133"M_A_CPU1_SA_DQ<25>";
134"M_A_CPU1_SA_DQ<24>";
135"M_A_CPU1_SA_DQ<23>";
136"M_A_CPU1_SA_DQ<22>";
137"M_A_CPU1_SA_DQ<21>";
138"M_A_CPU1_SA_DQ<20>";
139"M_A_CPU1_SA_DQ<31>";
140"M_A_CPU1_SA_DQ<30>";
141"M_A_CPU1_SB_DQ<3>";
142"M_A_CPU1_SA_DQ<3>";
143"M_A_CPU1_SA_DQ<2>";
144"M_A_CPU1_SA_DQ<1>";
145"M_A_CPU1_SA_DQ<0>";
146"M_A_CPU1_SA_DQ<17>";
147"M_A_CPU1_SA_DQ<16>";
148"M_A_CPU1_SA_DQ<15>";
149"M_A_CPU1_SA_DQ<14>";
150"M_A_CPU1_SA_DQ<13>";
151"M_A_CPU1_SA_DQ<9>";
152"M_A_CPU1_SA_DQ<12>";
153"M_A_CPU1_SA_DQ<8>";
154"M_A_CPU1_SA_DQ<11>";
155"M_A_CPU1_SA_DQ<7>";
156"M_A_CPU1_SA_DQ<10>";
157"M_A_CPU1_SA_DQ<6>";
158"M_A_CPU1_SA_DQ<5>";
159"M_A_CPU1_SA_DQ<4>";
%"GENOA_SP5"
"1","(-4575,3675)","0","pure_quanta","I167";
;
LOCATION"U26"
$SEC"1"
CDS_SEC"1"
PART_TYPE"SMLF"
MATERIAL"IO"
VALUE"SOCKET6096_13568-001"
PART_NUMBER"DGA^6000030"
CDS_LIB"pure_quanta"
NEEDS_NO_SIZE"TRUE"
CDS_LMAN_SYM_OUTLINE"-650,2500,650,-2500";
"TEST40"
$PN"C60"12;
"TEST39A"
$PN"BF72"13;
"MA1_CLK_L"
$PN"BG74"0;
"MA0_CLK_L"
$PN"BD74"16;
"MA1_CLK_H"
$PN"BF74"0;
"MAB_DQS_H9"
$PN"BV74"41;
"MA0_CLK_H"
$PN"BC74"15;
"MAB_PAR"
$PN"BL74"24;
"MAA_PAR"
$PN"BC73"20;
"MAA0_CS_L0"
$PN"AV74"17;
"MAA_DATA3"
$PN"G73"142;
"MAA_DQS_H6"
$PN"R73"60;
"MAB_CA6"
$PN"BK74"26;
"MAB_DATA2"
$PN"CC74"124;
"MAB_DATA17"
$PN"CR73"105;
"MAB_DATA28"
$PN"DD74"88;
"MAB_DQS_H0"
$PN"CD74"42;
"MAB_DQS_L4"
$PN"BW73"43;
"MAA_CA6"
$PN"BB72"27;
"MAA_DATA2"
$PN"F74"143;
"MAA_DQS_H5"
$PN"J73"61;
"MAA_DQS_L9"
$PN"AM72"62;
"MAB1_RSP_L"
$PN"BR74"0;
"MAB_CA5"
$PN"BK72"28;
"MAB_CHECK7"
$PN"BV72"80;
"MAB_DATA1"
$PN"CC73"125;
"MAB_DATA16"
$PN"CP74"106;
"MAB_DATA27"
$PN"DB72"89;
"MAB_DQS_L3"
$PN"DC74"44;
"MAA_CA5"
$PN"BB74"29;
"MAA_DATA1"
$PN"F72"144;
"MAA_DQS_H4"
$PN"AL74"63;
"MAA_DQS_L8"
$PN"AF72"64;
"MAB0_RSP_L"
$PN"BP74"23;
"MAB_CA4"
$PN"BJ73"30;
"MAB_CHECK6"
$PN"BU74"81;
"MAB_DATA0"
$PN"CB74"126;
"MAB_DATA15"
$PN"CP72"107;
"MAB_DATA26"
$PN"DA74"90;
"MAB_DQS_L2"
$PN"CU74"45;
"MAA_CA4"
$PN"BA74"31;
"MAA_DATA0"
$PN"E74"145;
"MAA_DQS_H3"
$PN"AE74"65;
"MAA_DQS_L7"
$PN"Y72"66;
"MAB_CA3"
$PN"BJ74"32;
"MAB_CHECK5"
$PN"BU73"82;
"MAB_DATA14"
$PN"CN74"108;
"MAB_DATA25"
$PN"DA73"91;
"MAB_DQS_L1"
$PN"CL74"46;
"MAA_CA3"
$PN"BA73"33;
"MAA_DATA19"
$PN"W73"127;
"MAA_DQS_H2"
$PN"W74"67;
"MAA_DQS_L6"
$PN"P72"68;
"MAB_CA2"
$PN"BH74"34;
"MAB_CHECK4"
$PN"BT74"83;
"MAB_DATA13"
$PN"CN73"109;
"MAB_DATA24"
$PN"CY74"92;
"MAB_DQS_L0"
$PN"CE74"47;
"MAA_CA2"
$PN"AY72"35;
"MAA_DATA18"
$PN"V74"128;
"MAA_DATA29"
$PN"AH72"129;
"MAA_DQS_H1"
$PN"N74"69;
"MAA_DQS_L5"
$PN"H72"70;
"MAB_CA1"
$PN"BH72"36;
"MAB_CHECK3"
$PN"CB72"84;
"MAB_DATA12"
$PN"CM74"110;
"MAB_DATA23"
$PN"CY72"93;
"MAA_CA1"
$PN"AY74"37;
"MAA_DATA17"
$PN"V72"146;
"MAA_DATA28"
$PN"AG74"130;
"MAA_DQS_H0"
$PN"G74"71;
"MAA_DQS_L4"
$PN"AM74"72;
"MAB_CA0"
$PN"BG73"38;
"MAB_CHECK2"
$PN"CA74"85;
"MAB_DATA11"
$PN"CK72"111;
"MAB_DATA22"
$PN"CW74"112;
"MAA1_RSP_L"
$PN"BP72"0;
"MAA_CA0"
$PN"AW74"39;
"MAA_CHECK7"
$PN"AR73"94;
"MAA_DATA16"
$PN"U74"147;
"MAA_DATA27"
$PN"AE73"131;
"MAA_DQS_L3"
$PN"AF74"73;
"MAB_CHECK1"
$PN"CA73"86;
"MAB_DATA10"
$PN"CJ74"113;
"MAB_DATA21"
$PN"CW73"114;
"MAA0_RSP_L"
$PN"BN73"19;
"MAA_CHECK6"
$PN"AP74"95;
"MAA_DATA15"
$PN"U73"148;
"MAA_DATA26"
$PN"AD74"132;
"MAA_DQS_L2"
$PN"Y74"74;
"MAB_CHECK0"
$PN"BY74"87;
"MAB_DATA20"
$PN"CV74"115;
"MAB_DATA31"
$PN"DF74"96;
"MAA_CHECK5"
$PN"AP72"97;
"MAA_DATA14"
$PN"T74"149;
"MAA_DATA25"
$PN"AD72"133;
"MAA_DQS_L1"
$PN"P74"75;
"MAB1_CS_L1"
$PN"BM74"0;
"MAB_DATA30"
$PN"DE74"98;
"MAB_DQS_H8"
$PN"DD72"48;
"MAA_CHECK4"
$PN"AN74"99;
"MAA_DATA13"
$PN"T72"150;
"MAA_DATA24"
$PN"AC74"134;
"MAA_DQS_L0"
$PN"H74"76;
"MAB0_CS_L1"
$PN"BN74"22;
"MAB1_CS_L0"
$PN"BL73"0;
"MAB_DATA9"
$PN"CJ73"116;
"MAB_DQS_H7"
$PN"CV72"49;
"MAA_CHECK3"
$PN"AL73"100;
"MAA_DATA9"
$PN"M72"151;
"MAA_DATA12"
$PN"R74"152;
"MAA_DATA23"
$PN"AC73"135;
"MAB0_CS_L0"
$PN"BM72"21;
"MAB_DATA8"
$PN"CH74"117;
"MAB_DQS_H6"
$PN"CM72"50;
"MAA_CHECK2"
$PN"AK74"101;
"MAA_DATA8"
$PN"L74"153;
"MAA_DATA11"
$PN"N73"154;
"MAA_DATA22"
$PN"AB74"136;
"MAB_DATA7"
$PN"CH72"118;
"MAB_DQS_H5"
$PN"CF72"51;
"MAB_DQS_L9"
$PN"BW74"40;
"MAA_CHECK1"
$PN"AK72"102;
"MAA_DATA7"
$PN"L73"155;
"MAA_DATA10"
$PN"M74"156;
"MAA_DATA21"
$PN"AB72"137;
"MAB_DATA6"
$PN"CG74"119;
"MAB_DQS_H4"
$PN"BY72"52;
"MAB_DQS_L8"
$PN"DC73"53;
"MAA_CHECK0"
$PN"AJ74"103;
"MAA_DATA6"
$PN"K74"157;
"MAA_DATA20"
$PN"AA74"138;
"MAA_DATA31"
$PN"AJ73"139;
"MAA_DQS_H9"
$PN"AN73"77;
"MAB_DATA5"
$PN"CG73"120;
"MAB_DQS_H3"
$PN"DB74"54;
"MAB_DQS_L7"
$PN"CU73"55;
"MAA1_CS_L1"
$PN"AV72"0;
"MAA_DATA5"
$PN"K72"158;
"MAA_DATA30"
$PN"AH74"140;
"MAA_DQS_H8"
$PN"AG73"78;
"MAB_DATA4"
$PN"CF74"121;
"MAB_DATA19"
$PN"CT72"122;
"MAB_DQS_H2"
$PN"CT74"56;
"MAB_DQS_L6"
$PN"CL73"57;
"MAA0_CS_L1"
$PN"AW73"18;
"MAA1_CS_L0"
$PN"AU74"0;
"MAA_DATA4"
$PN"J74"159;
"MAA_DQS_H7"
$PN"AA73"79;
"MAB_DATA3"
$PN"CD72"141;
"MAB_DATA18"
$PN"CR74"123;
"MAB_DATA29"
$PN"DE73"104;
"MAB_DQS_H1"
$PN"CK74"58;
"MAB_DQS_L5"
$PN"CE73"59;
"MA_RESET_L"
$PN"AT74"25;
"MA_ALERT_L"
$PN"AR74"14;
%"TAP"
"1","(-3300,6025)","0","mstr_standard","I170";
;
CDS_LIB"mstr_standard"
BODY_TYPE"PLUMBING"
HDL_TAP"TRUE";
"B \NAC \NWC"1;
"S \NAC"
BN"1"144;
%"TAP"
"1","(-3300,6075)","0","mstr_standard","I171";
;
CDS_LIB"mstr_standard"
BODY_TYPE"PLUMBING"
HDL_TAP"TRUE";
"B \NAC \NWC"1;
"S \NAC"
BN"0"145;
%"TAP"
"1","(-3300,5975)","0","mstr_standard","I172";
;
CDS_LIB"mstr_standard"
BODY_TYPE"PLUMBING"
HDL_TAP"TRUE";
"B \NAC \NWC"1;
"S \NAC"
BN"2"143;
%"TAP"
"1","(-3300,5925)","0","mstr_standard","I173";
;
CDS_LIB"mstr_standard"
BODY_TYPE"PLUMBING"
HDL_TAP"TRUE";
"B \NAC \NWC"1;
"S \NAC"
BN"3"142;
%"TAP"
"1","(-3300,5825)","0","mstr_standard","I174";
;
CDS_LIB"mstr_standard"
BODY_TYPE"PLUMBING"
HDL_TAP"TRUE";
"B \NAC \NWC"1;
"S \NAC"
BN"5"158;
%"TAP"
"1","(-3300,5875)","0","mstr_standard","I175";
;
CDS_LIB"mstr_standard"
BODY_TYPE"PLUMBING"
HDL_TAP"TRUE";
"B \NAC \NWC"1;
"S \NAC"
BN"4"159;
%"TAP"
"1","(-3300,5775)","0","mstr_standard","I176";
;
CDS_LIB"mstr_standard"
BODY_TYPE"PLUMBING"
HDL_TAP"TRUE";
"B \NAC \NWC"1;
"S \NAC"
BN"6"157;
%"TAP"
"1","(-3300,5725)","0","mstr_standard","I177";
;
CDS_LIB"mstr_standard"
BODY_TYPE"PLUMBING"
HDL_TAP"TRUE";
"B \NAC \NWC"1;
"S \NAC"
BN"7"155;
%"TAP"
"1","(-3300,5575)","0","mstr_standard","I178";
;
CDS_LIB"mstr_standard"
BODY_TYPE"PLUMBING"
HDL_TAP"TRUE";
"B \NAC \NWC"1;
"S \NAC"
BN"9"151;
%"TAP"
"1","(-3300,5625)","0","mstr_standard","I179";
;
CDS_LIB"mstr_standard"
BODY_TYPE"PLUMBING"
HDL_TAP"TRUE";
"B \NAC \NWC"1;
"S \NAC"
BN"8"153;
%"TAP"
"1","(-3300,5525)","0","mstr_standard","I180";
;
CDS_LIB"mstr_standard"
BODY_TYPE"PLUMBING"
HDL_TAP"TRUE";
"B \NAC \NWC"1;
"S \NAC"
BN"10"156;
%"TAP"
"1","(-3300,5425)","0","mstr_standard","I181";
;
CDS_LIB"mstr_standard"
BODY_TYPE"PLUMBING"
HDL_TAP"TRUE";
"B \NAC \NWC"1;
"S \NAC"
BN"12"152;
%"TAP"
"1","(-3300,5475)","0","mstr_standard","I182";
;
CDS_LIB"mstr_standard"
BODY_TYPE"PLUMBING"
HDL_TAP"TRUE";
"B \NAC \NWC"1;
"S \NAC"
BN"11"154;
%"TAP"
"1","(-3300,5325)","0","mstr_standard","I183";
;
CDS_LIB"mstr_standard"
BODY_TYPE"PLUMBING"
HDL_TAP"TRUE";
"B \NAC \NWC"1;
"S \NAC"
BN"14"149;
%"TAP"
"1","(-3300,5375)","0","mstr_standard","I184";
;
CDS_LIB"mstr_standard"
BODY_TYPE"PLUMBING"
HDL_TAP"TRUE";
"B \NAC \NWC"1;
"S \NAC"
BN"13"150;
%"TAP"
"1","(-3300,5275)","0","mstr_standard","I185";
;
CDS_LIB"mstr_standard"
BODY_TYPE"PLUMBING"
HDL_TAP"TRUE";
"B \NAC \NWC"1;
"S \NAC"
BN"15"148;
%"TAP"
"1","(-3300,5125)","0","mstr_standard","I186";
;
CDS_LIB"mstr_standard"
BODY_TYPE"PLUMBING"
HDL_TAP"TRUE";
"B \NAC \NWC"1;
"S \NAC"
BN"17"146;
%"TAP"
"1","(-3300,5175)","0","mstr_standard","I187";
;
CDS_LIB"mstr_standard"
BODY_TYPE"PLUMBING"
HDL_TAP"TRUE";
"B \NAC \NWC"1;
"S \NAC"
BN"16"147;
%"TAP"
"1","(-3300,5075)","0","mstr_standard","I188";
;
CDS_LIB"mstr_standard"
BODY_TYPE"PLUMBING"
HDL_TAP"TRUE";
"B \NAC \NWC"1;
"S \NAC"
BN"18"128;
%"TAP"
"1","(-3300,5025)","0","mstr_standard","I189";
;
CDS_LIB"mstr_standard"
BODY_TYPE"PLUMBING"
HDL_TAP"TRUE";
"B \NAC \NWC"1;
"S \NAC"
BN"19"127;
%"TAP"
"1","(-3300,4975)","0","mstr_standard","I190";
;
CDS_LIB"mstr_standard"
BODY_TYPE"PLUMBING"
HDL_TAP"TRUE";
"B \NAC \NWC"1;
"S \NAC"
BN"20"138;
%"TAP"
"1","(-3300,4875)","0","mstr_standard","I191";
;
CDS_LIB"mstr_standard"
BODY_TYPE"PLUMBING"
HDL_TAP"TRUE";
"B \NAC \NWC"1;
"S \NAC"
BN"22"136;
%"TAP"
"1","(-3300,4925)","0","mstr_standard","I192";
;
CDS_LIB"mstr_standard"
BODY_TYPE"PLUMBING"
HDL_TAP"TRUE";
"B \NAC \NWC"1;
"S \NAC"
BN"21"137;
%"TAP"
"1","(-3300,4825)","0","mstr_standard","I193";
;
CDS_LIB"mstr_standard"
BODY_TYPE"PLUMBING"
HDL_TAP"TRUE";
"B \NAC \NWC"1;
"S \NAC"
BN"23"135;
%"TAP"
"1","(-3300,4675)","0","mstr_standard","I194";
;
CDS_LIB"mstr_standard"
BODY_TYPE"PLUMBING"
HDL_TAP"TRUE";
"B \NAC \NWC"1;
"S \NAC"
BN"25"133;
%"TAP"
"1","(-3300,4725)","0","mstr_standard","I195";
;
CDS_LIB"mstr_standard"
BODY_TYPE"PLUMBING"
HDL_TAP"TRUE";
"B \NAC \NWC"1;
"S \NAC"
BN"24"134;
%"TAP"
"1","(-3300,4625)","0","mstr_standard","I196";
;
CDS_LIB"mstr_standard"
BODY_TYPE"PLUMBING"
HDL_TAP"TRUE";
"B \NAC \NWC"1;
"S \NAC"
BN"26"132;
%"TAP"
"1","(-3300,4575)","0","mstr_standard","I197";
;
CDS_LIB"mstr_standard"
BODY_TYPE"PLUMBING"
HDL_TAP"TRUE";
"B \NAC \NWC"1;
"S \NAC"
BN"27"131;
%"TAP"
"1","(-3300,4525)","0","mstr_standard","I198";
;
CDS_LIB"mstr_standard"
BODY_TYPE"PLUMBING"
HDL_TAP"TRUE";
"B \NAC \NWC"1;
"S \NAC"
BN"28"130;
%"TAP"
"1","(-3300,4475)","0","mstr_standard","I199";
;
CDS_LIB"mstr_standard"
BODY_TYPE"PLUMBING"
HDL_TAP"TRUE";
"B \NAC \NWC"1;
"S \NAC"
BN"29"129;
%"TAP"
"1","(-3300,4425)","0","mstr_standard","I200";
;
CDS_LIB"mstr_standard"
BODY_TYPE"PLUMBING"
HDL_TAP"TRUE";
"B \NAC \NWC"1;
"S \NAC"
BN"30"140;
%"TAP"
"1","(-3300,4375)","0","mstr_standard","I201";
;
CDS_LIB"mstr_standard"
BODY_TYPE"PLUMBING"
HDL_TAP"TRUE";
"B \NAC \NWC"1;
"S \NAC"
BN"31"139;
%"TAP"
"1","(-3300,4225)","0","mstr_standard","I202";
;
CDS_LIB"mstr_standard"
BODY_TYPE"PLUMBING"
HDL_TAP"TRUE";
"B \NAC \NWC"2;
"S \NAC"
BN"1"125;
%"TAP"
"1","(-3300,4275)","0","mstr_standard","I203";
;
CDS_LIB"mstr_standard"
BODY_TYPE"PLUMBING"
HDL_TAP"TRUE";
"B \NAC \NWC"2;
"S \NAC"
BN"0"126;
%"TAP"
"1","(-3300,4125)","0","mstr_standard","I204";
;
CDS_LIB"mstr_standard"
BODY_TYPE"PLUMBING"
HDL_TAP"TRUE";
"B \NAC \NWC"2;
"S \NAC"
BN"3"141;
%"TAP"
"1","(-3300,4175)","0","mstr_standard","I205";
;
CDS_LIB"mstr_standard"
BODY_TYPE"PLUMBING"
HDL_TAP"TRUE";
"B \NAC \NWC"2;
"S \NAC"
BN"2"124;
%"TAP"
"1","(-3300,4075)","0","mstr_standard","I207";
;
CDS_LIB"mstr_standard"
BODY_TYPE"PLUMBING"
HDL_TAP"TRUE";
"B \NAC \NWC"2;
"S \NAC"
BN"4"121;
%"TAP"
"1","(-3300,3975)","0","mstr_standard","I208";
;
CDS_LIB"mstr_standard"
BODY_TYPE"PLUMBING"
HDL_TAP"TRUE";
"B \NAC \NWC"2;
"S \NAC"
BN"6"119;
%"TAP"
"1","(-3300,4025)","0","mstr_standard","I209";
;
CDS_LIB"mstr_standard"
BODY_TYPE"PLUMBING"
HDL_TAP"TRUE";
"B \NAC \NWC"2;
"S \NAC"
BN"5"120;
%"TAP"
"1","(-3300,3925)","0","mstr_standard","I210";
;
CDS_LIB"mstr_standard"
BODY_TYPE"PLUMBING"
HDL_TAP"TRUE";
"B \NAC \NWC"2;
"S \NAC"
BN"7"118;
%"TAP"
"1","(-3300,3825)","0","mstr_standard","I211";
;
CDS_LIB"mstr_standard"
BODY_TYPE"PLUMBING"
HDL_TAP"TRUE";
"B \NAC \NWC"2;
"S \NAC"
BN"8"117;
%"TAP"
"1","(-3300,3725)","0","mstr_standard","I212";
;
CDS_LIB"mstr_standard"
BODY_TYPE"PLUMBING"
HDL_TAP"TRUE";
"B \NAC \NWC"2;
"S \NAC"
BN"10"113;
%"TAP"
"1","(-3300,3775)","0","mstr_standard","I213";
;
CDS_LIB"mstr_standard"
BODY_TYPE"PLUMBING"
HDL_TAP"TRUE";
"B \NAC \NWC"2;
"S \NAC"
BN"9"116;
%"TAP"
"1","(-3300,3675)","0","mstr_standard","I214";
;
CDS_LIB"mstr_standard"
BODY_TYPE"PLUMBING"
HDL_TAP"TRUE";
"B \NAC \NWC"2;
"S \NAC"
BN"11"111;
%"TAP"
"1","(-3300,3625)","0","mstr_standard","I215";
;
CDS_LIB"mstr_standard"
BODY_TYPE"PLUMBING"
HDL_TAP"TRUE";
"B \NAC \NWC"2;
"S \NAC"
BN"12"110;
%"TAP"
"1","(-3300,3525)","0","mstr_standard","I216";
;
CDS_LIB"mstr_standard"
BODY_TYPE"PLUMBING"
HDL_TAP"TRUE";
"B \NAC \NWC"2;
"S \NAC"
BN"14"108;
%"TAP"
"1","(-3300,3575)","0","mstr_standard","I217";
;
CDS_LIB"mstr_standard"
BODY_TYPE"PLUMBING"
HDL_TAP"TRUE";
"B \NAC \NWC"2;
"S \NAC"
BN"13"109;
%"TAP"
"1","(-3300,3475)","0","mstr_standard","I218";
;
CDS_LIB"mstr_standard"
BODY_TYPE"PLUMBING"
HDL_TAP"TRUE";
"B \NAC \NWC"2;
"S \NAC"
BN"15"107;
%"TAP"
"1","(-3300,3375)","0","mstr_standard","I219";
;
CDS_LIB"mstr_standard"
BODY_TYPE"PLUMBING"
HDL_TAP"TRUE";
"B \NAC \NWC"2;
"S \NAC"
BN"16"106;
%"TAP"
"1","(-3300,3275)","0","mstr_standard","I220";
;
CDS_LIB"mstr_standard"
BODY_TYPE"PLUMBING"
HDL_TAP"TRUE";
"B \NAC \NWC"2;
"S \NAC"
BN"18"123;
%"TAP"
"1","(-3300,3325)","0","mstr_standard","I221";
;
CDS_LIB"mstr_standard"
BODY_TYPE"PLUMBING"
HDL_TAP"TRUE";
"B \NAC \NWC"2;
"S \NAC"
BN"17"105;
%"TAP"
"1","(-3300,3225)","0","mstr_standard","I222";
;
CDS_LIB"mstr_standard"
BODY_TYPE"PLUMBING"
HDL_TAP"TRUE";
"B \NAC \NWC"2;
"S \NAC"
BN"19"122;
%"TAP"
"1","(-3300,3175)","0","mstr_standard","I223";
;
CDS_LIB"mstr_standard"
BODY_TYPE"PLUMBING"
HDL_TAP"TRUE";
"B \NAC \NWC"2;
"S \NAC"
BN"20"115;
%"TAP"
"1","(-3300,3125)","0","mstr_standard","I224";
;
CDS_LIB"mstr_standard"
BODY_TYPE"PLUMBING"
HDL_TAP"TRUE";
"B \NAC \NWC"2;
"S \NAC"
BN"21"114;
%"TAP"
"1","(-3300,3075)","0","mstr_standard","I225";
;
CDS_LIB"mstr_standard"
BODY_TYPE"PLUMBING"
HDL_TAP"TRUE";
"B \NAC \NWC"2;
"S \NAC"
BN"22"112;
%"TAP"
"1","(-3300,3025)","0","mstr_standard","I226";
;
CDS_LIB"mstr_standard"
BODY_TYPE"PLUMBING"
HDL_TAP"TRUE";
"B \NAC \NWC"2;
"S \NAC"
BN"23"93;
%"TAP"
"1","(-3300,2925)","0","mstr_standard","I227";
;
CDS_LIB"mstr_standard"
BODY_TYPE"PLUMBING"
HDL_TAP"TRUE";
"B \NAC \NWC"2;
"S \NAC"
BN"24"92;
%"TAP"
"1","(-3300,2875)","0","mstr_standard","I228";
;
CDS_LIB"mstr_standard"
BODY_TYPE"PLUMBING"
HDL_TAP"TRUE";
"B \NAC \NWC"2;
"S \NAC"
BN"25"91;
%"TAP"
"1","(-3300,2825)","0","mstr_standard","I229";
;
CDS_LIB"mstr_standard"
BODY_TYPE"PLUMBING"
HDL_TAP"TRUE";
"B \NAC \NWC"2;
"S \NAC"
BN"26"90;
%"TAP"
"1","(-3300,2775)","0","mstr_standard","I230";
;
CDS_LIB"mstr_standard"
BODY_TYPE"PLUMBING"
HDL_TAP"TRUE";
"B \NAC \NWC"2;
"S \NAC"
BN"27"89;
%"TAP"
"1","(-3300,2725)","0","mstr_standard","I231";
;
CDS_LIB"mstr_standard"
BODY_TYPE"PLUMBING"
HDL_TAP"TRUE";
"B \NAC \NWC"2;
"S \NAC"
BN"28"88;
%"TAP"
"1","(-3300,2675)","0","mstr_standard","I232";
;
CDS_LIB"mstr_standard"
BODY_TYPE"PLUMBING"
HDL_TAP"TRUE";
"B \NAC \NWC"2;
"S \NAC"
BN"29"104;
%"TAP"
"1","(-3300,2625)","0","mstr_standard","I233";
;
CDS_LIB"mstr_standard"
BODY_TYPE"PLUMBING"
HDL_TAP"TRUE";
"B \NAC \NWC"2;
"S \NAC"
BN"30"98;
%"TAP"
"1","(-3300,2575)","0","mstr_standard","I234";
;
CDS_LIB"mstr_standard"
BODY_TYPE"PLUMBING"
HDL_TAP"TRUE";
"B \NAC \NWC"2;
"S \NAC"
BN"31"96;
%"TAP"
"1","(-3300,2475)","0","mstr_standard","I235";
;
CDS_LIB"mstr_standard"
BODY_TYPE"PLUMBING"
HDL_TAP"TRUE";
"B \NAC \NWC"3;
"S \NAC"
BN"0"103;
%"TAP"
"1","(-3300,2375)","0","mstr_standard","I236";
;
CDS_LIB"mstr_standard"
BODY_TYPE"PLUMBING"
HDL_TAP"TRUE";
"B \NAC \NWC"3;
"S \NAC"
BN"2"101;
%"TAP"
"1","(-3300,2425)","0","mstr_standard","I237";
;
CDS_LIB"mstr_standard"
BODY_TYPE"PLUMBING"
HDL_TAP"TRUE";
"B \NAC \NWC"3;
"S \NAC"
BN"1"102;
%"TAP"
"1","(-3300,2325)","0","mstr_standard","I238";
;
CDS_LIB"mstr_standard"
BODY_TYPE"PLUMBING"
HDL_TAP"TRUE";
"B \NAC \NWC"3;
"S \NAC"
BN"3"100;
%"TAP"
"1","(-3300,2275)","0","mstr_standard","I239";
;
CDS_LIB"mstr_standard"
BODY_TYPE"PLUMBING"
HDL_TAP"TRUE";
"B \NAC \NWC"3;
"S \NAC"
BN"4"99;
%"TAP"
"1","(-3300,2225)","0","mstr_standard","I240";
;
CDS_LIB"mstr_standard"
BODY_TYPE"PLUMBING"
HDL_TAP"TRUE";
"B \NAC \NWC"3;
"S \NAC"
BN"5"97;
%"TAP"
"1","(-3300,2175)","0","mstr_standard","I241";
;
CDS_LIB"mstr_standard"
BODY_TYPE"PLUMBING"
HDL_TAP"TRUE";
"B \NAC \NWC"3;
"S \NAC"
BN"6"95;
%"TAP"
"1","(-3300,2125)","0","mstr_standard","I242";
;
CDS_LIB"mstr_standard"
BODY_TYPE"PLUMBING"
HDL_TAP"TRUE";
"B \NAC \NWC"3;
"S \NAC"
BN"7"94;
%"TAP"
"1","(-3300,2025)","0","mstr_standard","I244";
;
CDS_LIB"mstr_standard"
BODY_TYPE"PLUMBING"
HDL_TAP"TRUE";
"B \NAC \NWC"4;
"S \NAC"
BN"0"87;
%"TAP"
"1","(-3300,1975)","0","mstr_standard","I245";
;
CDS_LIB"mstr_standard"
BODY_TYPE"PLUMBING"
HDL_TAP"TRUE";
"B \NAC \NWC"4;
"S \NAC"
BN"1"86;
%"TAP"
"1","(-3300,1925)","0","mstr_standard","I246";
;
CDS_LIB"mstr_standard"
BODY_TYPE"PLUMBING"
HDL_TAP"TRUE";
"B \NAC \NWC"4;
"S \NAC"
BN"2"85;
%"TAP"
"1","(-3300,1825)","0","mstr_standard","I247";
;
CDS_LIB"mstr_standard"
BODY_TYPE"PLUMBING"
HDL_TAP"TRUE";
"B \NAC \NWC"4;
"S \NAC"
BN"4"83;
%"TAP"
"1","(-3300,1875)","0","mstr_standard","I248";
;
CDS_LIB"mstr_standard"
BODY_TYPE"PLUMBING"
HDL_TAP"TRUE";
"B \NAC \NWC"4;
"S \NAC"
BN"3"84;
%"TAP"
"1","(-3300,1775)","0","mstr_standard","I249";
;
CDS_LIB"mstr_standard"
BODY_TYPE"PLUMBING"
HDL_TAP"TRUE";
"B \NAC \NWC"4;
"S \NAC"
BN"5"82;
%"TAP"
"1","(-3300,1675)","0","mstr_standard","I250";
;
CDS_LIB"mstr_standard"
BODY_TYPE"PLUMBING"
HDL_TAP"TRUE";
"B \NAC \NWC"4;
"S \NAC"
BN"7"80;
%"TAP"
"1","(-3300,1725)","0","mstr_standard","I251";
;
CDS_LIB"mstr_standard"
BODY_TYPE"PLUMBING"
HDL_TAP"TRUE";
"B \NAC \NWC"4;
"S \NAC"
BN"6"81;
%"TAP"
"1","(-5725,6075)","2","mstr_standard","I252";
;
CDS_LIB"mstr_standard"
BODY_TYPE"PLUMBING"
HDL_TAP"TRUE";
"B \NAC \NWC"5;
"S \NAC"
BN"0"71;
%"TAP"
"1","(-5725,5975)","2","mstr_standard","I253";
;
CDS_LIB"mstr_standard"
BODY_TYPE"PLUMBING"
HDL_TAP"TRUE";
"B \NAC \NWC"5;
"S \NAC"
BN"1"69;
%"TAP"
"1","(-5725,5875)","2","mstr_standard","I254";
;
CDS_LIB"mstr_standard"
BODY_TYPE"PLUMBING"
HDL_TAP"TRUE";
"B \NAC \NWC"5;
"S \NAC"
BN"2"67;
%"TAP"
"1","(-5925,6025)","2","mstr_standard","I255";
;
CDS_LIB"mstr_standard"
BODY_TYPE"PLUMBING"
HDL_TAP"TRUE";
"B \NAC \NWC"9;
"S \NAC"
BN"0"76;
%"TAP"
"1","(-5925,5925)","2","mstr_standard","I256";
;
CDS_LIB"mstr_standard"
BODY_TYPE"PLUMBING"
HDL_TAP"TRUE";
"B \NAC \NWC"9;
"S \NAC"
BN"1"75;
%"TAP"
"1","(-5725,5775)","2","mstr_standard","I257";
;
CDS_LIB"mstr_standard"
BODY_TYPE"PLUMBING"
HDL_TAP"TRUE";
"B \NAC \NWC"5;
"S \NAC"
BN"3"65;
%"TAP"
"1","(-5725,5675)","2","mstr_standard","I258";
;
CDS_LIB"mstr_standard"
BODY_TYPE"PLUMBING"
HDL_TAP"TRUE";
"B \NAC \NWC"5;
"S \NAC"
BN"4"63;
%"TAP"
"1","(-5925,5825)","2","mstr_standard","I259";
;
CDS_LIB"mstr_standard"
BODY_TYPE"PLUMBING"
HDL_TAP"TRUE";
"B \NAC \NWC"9;
"S \NAC"
BN"2"74;
%"TAP"
"1","(-5925,5725)","2","mstr_standard","I260";
;
CDS_LIB"mstr_standard"
BODY_TYPE"PLUMBING"
HDL_TAP"TRUE";
"B \NAC \NWC"9;
"S \NAC"
BN"3"73;
%"TAP"
"1","(-5725,5575)","2","mstr_standard","I261";
;
CDS_LIB"mstr_standard"
BODY_TYPE"PLUMBING"
HDL_TAP"TRUE";
"B \NAC \NWC"5;
"S \NAC"
BN"5"61;
%"TAP"
"1","(-5725,5375)","2","mstr_standard","I262";
;
CDS_LIB"mstr_standard"
BODY_TYPE"PLUMBING"
HDL_TAP"TRUE";
"B \NAC \NWC"5;
"S \NAC"
BN"7"79;
%"TAP"
"1","(-5725,5475)","2","mstr_standard","I263";
;
CDS_LIB"mstr_standard"
BODY_TYPE"PLUMBING"
HDL_TAP"TRUE";
"B \NAC \NWC"5;
"S \NAC"
BN"6"60;
%"TAP"
"1","(-5925,5625)","2","mstr_standard","I264";
;
CDS_LIB"mstr_standard"
BODY_TYPE"PLUMBING"
HDL_TAP"TRUE";
"B \NAC \NWC"9;
"S \NAC"
BN"4"72;
%"TAP"
"1","(-5925,5525)","2","mstr_standard","I265";
;
CDS_LIB"mstr_standard"
BODY_TYPE"PLUMBING"
HDL_TAP"TRUE";
"B \NAC \NWC"9;
"S \NAC"
BN"5"70;
%"TAP"
"1","(-5925,5425)","2","mstr_standard","I266";
;
CDS_LIB"mstr_standard"
BODY_TYPE"PLUMBING"
HDL_TAP"TRUE";
"B \NAC \NWC"9;
"S \NAC"
BN"6"68;
%"TAP"
"1","(-5725,5275)","2","mstr_standard","I267";
;
CDS_LIB"mstr_standard"
BODY_TYPE"PLUMBING"
HDL_TAP"TRUE";
"B \NAC \NWC"5;
"S \NAC"
BN"8"78;
%"TAP"
"1","(-5725,5175)","2","mstr_standard","I268";
;
CDS_LIB"mstr_standard"
BODY_TYPE"PLUMBING"
HDL_TAP"TRUE";
"B \NAC \NWC"5;
"S \NAC"
BN"9"77;
%"TAP"
"1","(-5925,5325)","2","mstr_standard","I269";
;
CDS_LIB"mstr_standard"
BODY_TYPE"PLUMBING"
HDL_TAP"TRUE";
"B \NAC \NWC"9;
"S \NAC"
BN"7"66;
%"TAP"
"1","(-5925,5225)","2","mstr_standard","I270";
;
CDS_LIB"mstr_standard"
BODY_TYPE"PLUMBING"
HDL_TAP"TRUE";
"B \NAC \NWC"9;
"S \NAC"
BN"8"64;
%"TAP"
"1","(-5925,5125)","2","mstr_standard","I271";
;
CDS_LIB"mstr_standard"
BODY_TYPE"PLUMBING"
HDL_TAP"TRUE";
"B \NAC \NWC"9;
"S \NAC"
BN"9"62;
%"TAP"
"1","(-5725,5025)","2","mstr_standard","I272";
;
CDS_LIB"mstr_standard"
BODY_TYPE"PLUMBING"
HDL_TAP"TRUE";
"B \NAC \NWC"6;
"S \NAC"
BN"0"42;
%"TAP"
"1","(-5725,4925)","2","mstr_standard","I273";
;
CDS_LIB"mstr_standard"
BODY_TYPE"PLUMBING"
HDL_TAP"TRUE";
"B \NAC \NWC"6;
"S \NAC"
BN"1"58;
%"TAP"
"1","(-5925,4975)","2","mstr_standard","I274";
;
CDS_LIB"mstr_standard"
BODY_TYPE"PLUMBING"
HDL_TAP"TRUE";
"B \NAC \NWC"10;
"S \NAC"
BN"0"47;
%"TAP"
"1","(-5925,4875)","2","mstr_standard","I275";
;
CDS_LIB"mstr_standard"
BODY_TYPE"PLUMBING"
HDL_TAP"TRUE";
"B \NAC \NWC"10;
"S \NAC"
BN"1"46;
%"TAP"
"1","(-5725,4825)","2","mstr_standard","I276";
;
CDS_LIB"mstr_standard"
BODY_TYPE"PLUMBING"
HDL_TAP"TRUE";
"B \NAC \NWC"6;
"S \NAC"
BN"2"56;
%"TAP"
"1","(-5725,4725)","2","mstr_standard","I277";
;
CDS_LIB"mstr_standard"
BODY_TYPE"PLUMBING"
HDL_TAP"TRUE";
"B \NAC \NWC"6;
"S \NAC"
BN"3"54;
%"TAP"
"1","(-5725,4625)","2","mstr_standard","I278";
;
CDS_LIB"mstr_standard"
BODY_TYPE"PLUMBING"
HDL_TAP"TRUE";
"B \NAC \NWC"6;
"S \NAC"
BN"4"52;
%"TAP"
"1","(-5925,4775)","2","mstr_standard","I279";
;
CDS_LIB"mstr_standard"
BODY_TYPE"PLUMBING"
HDL_TAP"TRUE";
"B \NAC \NWC"10;
"S \NAC"
BN"2"45;
%"TAP"
"1","(-5925,4675)","2","mstr_standard","I280";
;
CDS_LIB"mstr_standard"
BODY_TYPE"PLUMBING"
HDL_TAP"TRUE";
"B \NAC \NWC"10;
"S \NAC"
BN"3"44;
%"TAP"
"1","(-5725,4525)","2","mstr_standard","I281";
;
CDS_LIB"mstr_standard"
BODY_TYPE"PLUMBING"
HDL_TAP"TRUE";
"B \NAC \NWC"6;
"S \NAC"
BN"5"51;
%"TAP"
"1","(-5725,4425)","2","mstr_standard","I282";
;
CDS_LIB"mstr_standard"
BODY_TYPE"PLUMBING"
HDL_TAP"TRUE";
"B \NAC \NWC"6;
"S \NAC"
BN"6"50;
%"TAP"
"1","(-5925,4575)","2","mstr_standard","I283";
;
CDS_LIB"mstr_standard"
BODY_TYPE"PLUMBING"
HDL_TAP"TRUE";
"B \NAC \NWC"10;
"S \NAC"
BN"4"43;
%"TAP"
"1","(-5925,4475)","2","mstr_standard","I284";
;
CDS_LIB"mstr_standard"
BODY_TYPE"PLUMBING"
HDL_TAP"TRUE";
"B \NAC \NWC"10;
"S \NAC"
BN"5"59;
%"TAP"
"1","(-5925,4375)","2","mstr_standard","I285";
;
CDS_LIB"mstr_standard"
BODY_TYPE"PLUMBING"
HDL_TAP"TRUE";
"B \NAC \NWC"10;
"S \NAC"
BN"6"57;
%"TAP"
"1","(-5725,4325)","2","mstr_standard","I286";
;
CDS_LIB"mstr_standard"
BODY_TYPE"PLUMBING"
HDL_TAP"TRUE";
"B \NAC \NWC"6;
"S \NAC"
BN"7"49;
%"TAP"
"1","(-5725,4225)","2","mstr_standard","I287";
;
CDS_LIB"mstr_standard"
BODY_TYPE"PLUMBING"
HDL_TAP"TRUE";
"B \NAC \NWC"6;
"S \NAC"
BN"8"48;
%"TAP"
"1","(-5725,4125)","2","mstr_standard","I288";
;
CDS_LIB"mstr_standard"
BODY_TYPE"PLUMBING"
HDL_TAP"TRUE";
"B \NAC \NWC"6;
"S \NAC"
BN"9"41;
%"TAP"
"1","(-5925,4275)","2","mstr_standard","I289";
;
CDS_LIB"mstr_standard"
BODY_TYPE"PLUMBING"
HDL_TAP"TRUE";
"B \NAC \NWC"10;
"S \NAC"
BN"7"55;
%"TAP"
"1","(-5925,4175)","2","mstr_standard","I290";
;
CDS_LIB"mstr_standard"
BODY_TYPE"PLUMBING"
HDL_TAP"TRUE";
"B \NAC \NWC"10;
"S \NAC"
BN"8"53;
%"TAP"
"1","(-5925,4075)","2","mstr_standard","I295";
;
CDS_LIB"mstr_standard"
BODY_TYPE"PLUMBING"
HDL_TAP"TRUE";
"B \NAC \NWC"10;
"S \NAC"
BN"9"40;
%"TAP"
"1","(-5925,3925)","2","mstr_standard","I296";
;
CDS_LIB"mstr_standard"
BODY_TYPE"PLUMBING"
HDL_TAP"TRUE";
"B \NAC \NWC"7;
"S \NAC"
BN"0"39;
%"TAP"
"1","(-5925,3875)","2","mstr_standard","I297";
;
CDS_LIB"mstr_standard"
BODY_TYPE"PLUMBING"
HDL_TAP"TRUE";
"B \NAC \NWC"7;
"S \NAC"
BN"1"37;
%"TAP"
"1","(-5925,3825)","2","mstr_standard","I298";
;
CDS_LIB"mstr_standard"
BODY_TYPE"PLUMBING"
HDL_TAP"TRUE";
"B \NAC \NWC"7;
"S \NAC"
BN"2"35;
%"TAP"
"1","(-5925,3775)","2","mstr_standard","I299";
;
CDS_LIB"mstr_standard"
BODY_TYPE"PLUMBING"
HDL_TAP"TRUE";
"B \NAC \NWC"7;
"S \NAC"
BN"3"33;
%"TAP"
"1","(-5925,3725)","2","mstr_standard","I300";
;
CDS_LIB"mstr_standard"
BODY_TYPE"PLUMBING"
HDL_TAP"TRUE";
"B \NAC \NWC"7;
"S \NAC"
BN"4"31;
%"TAP"
"1","(-5925,3675)","2","mstr_standard","I301";
;
CDS_LIB"mstr_standard"
BODY_TYPE"PLUMBING"
HDL_TAP"TRUE";
"B \NAC \NWC"7;
"S \NAC"
BN"5"29;
%"TAP"
"1","(-5925,3625)","2","mstr_standard","I302";
;
CDS_LIB"mstr_standard"
BODY_TYPE"PLUMBING"
HDL_TAP"TRUE";
"B \NAC \NWC"7;
"S \NAC"
BN"6"27;
%"TAP"
"1","(-5925,3475)","2","mstr_standard","I303";
;
CDS_LIB"mstr_standard"
BODY_TYPE"PLUMBING"
HDL_TAP"TRUE";
"B \NAC \NWC"8;
"S \NAC"
BN"1"36;
%"TAP"
"1","(-5925,3525)","2","mstr_standard","I304";
;
CDS_LIB"mstr_standard"
BODY_TYPE"PLUMBING"
HDL_TAP"TRUE";
"B \NAC \NWC"8;
"S \NAC"
BN"0"38;
%"TAP"
"1","(-5925,3425)","2","mstr_standard","I305";
;
CDS_LIB"mstr_standard"
BODY_TYPE"PLUMBING"
HDL_TAP"TRUE";
"B \NAC \NWC"8;
"S \NAC"
BN"2"34;
%"TAP"
"1","(-5925,3375)","2","mstr_standard","I306";
;
CDS_LIB"mstr_standard"
BODY_TYPE"PLUMBING"
HDL_TAP"TRUE";
"B \NAC \NWC"8;
"S \NAC"
BN"3"32;
%"TAP"
"1","(-5925,3325)","2","mstr_standard","I307";
;
CDS_LIB"mstr_standard"
BODY_TYPE"PLUMBING"
HDL_TAP"TRUE";
"B \NAC \NWC"8;
"S \NAC"
BN"4"30;
%"TAP"
"1","(-5925,3225)","2","mstr_standard","I308";
;
CDS_LIB"mstr_standard"
BODY_TYPE"PLUMBING"
HDL_TAP"TRUE";
"B \NAC \NWC"8;
"S \NAC"
BN"6"26;
%"TAP"
"1","(-5925,3275)","2","mstr_standard","I309";
;
CDS_LIB"mstr_standard"
BODY_TYPE"PLUMBING"
HDL_TAP"TRUE";
"B \NAC \NWC"8;
"S \NAC"
BN"5"28;
%"Q_RES"
"1","(-6600,2225)","0","pure_quanta","I322";
;
LOCATION"R500"
$SEC"1"
CDS_SEC"1"
TOLERANCE"1%"
VALUE"15   "
PART_NUMBER"CS01502FB11"
PACK_TYPE"0402LF"
CDS_LIB"pure_quanta"
WATTAGE"1/16W"
MATERIAL"CHIP";
"B"
$PN"2"14;
"A"
$PN"1"11;
END.
